G04 ================== begin FILE IDENTIFICATION RECORD ==================*
G04 Layout Name:  14545-sa.brd*
G04 Film Name:    BSMD*
G04 File Format:  Gerber RS274X*
G04 File Origin:  Cadence Allegro 16.5-S056*
G04 Origin Date:  Fri Aug 01 17:58:13 2014*
G04 *
G04 Layer:  VIA CLASS/PASTEMASK_BOTTOM*
G04 Layer:  PIN/PASTEMASK_BOTTOM*
G04 Layer:  PACKAGE GEOMETRY/PASTEMASK_BOTTOM*
G04 Layer:  DRAWING FORMAT/LAYER_PCB_STORY*
G04 Layer:  DRAWING FORMAT/LAYER_PAST_B*
G04 Layer:  BOARD GEOMETRY/PANEL_OUTLINE*
G04 *
G04 Offset:    (0.00 0.00)*
G04 Mirror:    No*
G04 Mode:      Positive*
G04 Rotation:  0*
G04 FullContactRelief:  No*
G04 UndefLineWidth:     6.00*
G04 ================== end FILE IDENTIFICATION RECORD ====================*
%FSLAX35Y35*MOIN*%
%IR0*IPPOS*OFA0.00000B0.00000*MIA0B0*SFA1.00000B1.00000*%
%ADD13R,.23X.032*%
%ADD12R,.142X.028*%
%ADD10R,.05X.05*%
%ADD11C,.086*%
%ADD14C,.02*%
%ADD15C,.006*%
G75*
%LPD*%
G75*
G36*
G01X1017308Y1473722D02*
Y1491397D01*
X991708D01*
Y1473722D01*
X1017308D01*
G37*
G36*
G01Y1453247D02*
Y1470922D01*
X991708D01*
Y1453247D01*
X1017308D01*
G37*
G36*
G01Y1433722D02*
Y1451397D01*
X991708D01*
Y1433722D01*
X1017308D01*
G37*
G36*
G01Y1553722D02*
Y1571397D01*
X991708D01*
Y1553722D01*
X1017308D01*
G37*
G36*
G01Y1533247D02*
Y1550922D01*
X991708D01*
Y1533247D01*
X1017308D01*
G37*
G36*
G01Y1513722D02*
Y1531397D01*
X991708D01*
Y1513722D01*
X1017308D01*
G37*
G36*
G01Y1493247D02*
Y1510922D01*
X991708D01*
Y1493247D01*
X1017308D01*
G37*
G36*
G01X1017307Y1593722D02*
Y1610922D01*
X991708D01*
Y1593722D01*
X1017307D01*
G37*
G36*
G01X1017308Y1573247D02*
Y1590922D01*
X991708D01*
Y1573247D01*
X1017308D01*
G37*
G54D10*
X-30766Y56622D03*
X-33866Y1947322D03*
X21499Y17050D03*
X1010999Y18550D03*
X1008999Y1968550D03*
X1073334Y50022D03*
G54D11*
X-39052Y28742D03*
X-43327Y310478D03*
X-39686Y917251D03*
X-38801Y1082342D03*
X-44886Y1294251D03*
X-43103Y1928864D03*
X1071932Y32074D03*
X1074813Y1348051D03*
X1076613Y1740651D03*
X1074813Y1957551D03*
G54D12*
X12560Y211435D03*
Y207498D03*
Y203561D03*
Y199624D03*
Y195687D03*
Y191750D03*
Y187813D03*
Y183876D03*
Y179939D03*
Y176002D03*
Y172065D03*
Y231121D03*
Y227184D03*
Y223247D03*
Y246869D03*
Y242932D03*
Y238995D03*
Y235058D03*
X12569Y395663D03*
Y391726D03*
Y387789D03*
Y383852D03*
Y379915D03*
Y375978D03*
Y372041D03*
Y478342D03*
Y474405D03*
Y470468D03*
Y466531D03*
Y462594D03*
Y458657D03*
Y454720D03*
Y450783D03*
Y446846D03*
Y442909D03*
Y438972D03*
Y435035D03*
Y431098D03*
Y427161D03*
Y423223D03*
Y411411D03*
Y407474D03*
Y403537D03*
Y399600D03*
Y561019D03*
Y557082D03*
Y553145D03*
Y549208D03*
Y545271D03*
Y541334D03*
Y537397D03*
Y533460D03*
Y529523D03*
Y525586D03*
Y521649D03*
Y517712D03*
Y513775D03*
Y509838D03*
Y505901D03*
Y501964D03*
Y498027D03*
Y494090D03*
Y490153D03*
Y486216D03*
Y482279D03*
Y643696D03*
Y639759D03*
Y635822D03*
Y631885D03*
Y627948D03*
Y624011D03*
Y620074D03*
Y616137D03*
Y612200D03*
Y604326D03*
Y608263D03*
Y600389D03*
Y596452D03*
Y592515D03*
Y584641D03*
Y588578D03*
Y580704D03*
Y576767D03*
Y572830D03*
Y568893D03*
Y564956D03*
Y698814D03*
Y694877D03*
Y690940D03*
Y687003D03*
Y683066D03*
Y679129D03*
Y675192D03*
Y671255D03*
Y667318D03*
Y663381D03*
Y659444D03*
Y655507D03*
Y651570D03*
Y647633D03*
X12560Y813010D03*
Y809073D03*
Y805136D03*
Y801199D03*
Y797262D03*
Y793325D03*
Y789388D03*
Y785451D03*
Y781514D03*
Y820884D03*
Y816947D03*
Y856318D03*
Y852381D03*
Y848444D03*
Y844507D03*
Y840570D03*
Y836633D03*
Y832696D03*
Y1195687D03*
Y1191750D03*
Y1187813D03*
Y1183876D03*
Y1179939D03*
Y1176002D03*
Y1172065D03*
Y1168128D03*
Y1164191D03*
Y1160254D03*
Y1156317D03*
Y1223247D03*
Y1219310D03*
Y1215373D03*
Y1211436D03*
Y1207499D03*
Y1231121D03*
Y1227184D03*
X12569Y1391726D03*
Y1387789D03*
Y1383852D03*
Y1379915D03*
Y1375978D03*
Y1372041D03*
Y1368104D03*
Y1364167D03*
Y1360230D03*
Y1356293D03*
Y1474405D03*
Y1470468D03*
Y1466531D03*
Y1462594D03*
Y1458657D03*
Y1454720D03*
Y1450783D03*
Y1446846D03*
Y1442909D03*
Y1438972D03*
Y1435035D03*
Y1431098D03*
Y1427161D03*
Y1423224D03*
Y1419287D03*
Y1415350D03*
Y1411413D03*
Y1407475D03*
Y1395663D03*
Y1557082D03*
Y1553145D03*
Y1549208D03*
Y1545271D03*
Y1541334D03*
Y1537397D03*
Y1533460D03*
Y1529523D03*
Y1525586D03*
Y1521649D03*
Y1517712D03*
Y1513775D03*
Y1509838D03*
Y1505901D03*
Y1501964D03*
Y1498027D03*
Y1494090D03*
Y1490153D03*
Y1486216D03*
Y1482279D03*
Y1478342D03*
Y1639759D03*
Y1635822D03*
Y1631885D03*
Y1627948D03*
Y1624011D03*
Y1620074D03*
Y1616137D03*
Y1612200D03*
Y1608263D03*
Y1604326D03*
Y1600389D03*
Y1596452D03*
Y1588578D03*
Y1592515D03*
Y1584641D03*
Y1580704D03*
Y1576767D03*
Y1568893D03*
Y1572830D03*
Y1564956D03*
Y1561019D03*
Y1683066D03*
Y1679129D03*
Y1675192D03*
Y1671255D03*
Y1667318D03*
Y1663381D03*
Y1659444D03*
Y1655507D03*
Y1651570D03*
Y1647633D03*
Y1643696D03*
X12560Y1805136D03*
Y1801199D03*
Y1797262D03*
Y1793325D03*
Y1789388D03*
Y1785451D03*
Y1781514D03*
Y1777577D03*
Y1773640D03*
Y1769703D03*
Y1765766D03*
Y1840570D03*
Y1836633D03*
Y1832696D03*
Y1828759D03*
Y1824822D03*
Y1820885D03*
Y1816948D03*
G54D13*
X1005807Y1636102D03*
Y1631102D03*
Y1626102D03*
Y1621102D03*
Y1676102D03*
Y1671102D03*
Y1666102D03*
Y1661102D03*
Y1656102D03*
Y1651102D03*
Y1646102D03*
Y1641102D03*
G54D14*
G01X-71137Y-139897D02*
Y-219897D01*
G01D02*
X1129963D01*
G01X-75137Y-123897D02*
G02I-12000J0D01*
G01X-80287D02*
G02I-6850J0D01*
G01X-87137Y-139897D02*
Y-107897D01*
G01X-71137Y-123897D02*
X-103137D01*
G01X-71137Y-139897D02*
X1129963D01*
G01X-71137Y-175397D02*
X1129963D01*
G01X342463Y-139897D02*
Y-219897D01*
G01X479963Y-139897D02*
Y-219897D01*
G01X594963Y-139897D02*
Y-219897D01*
G01X762463Y-139897D02*
Y-219897D01*
G01X932463Y-139897D02*
Y-219897D01*
G01X1129963Y-139897D02*
Y-219897D01*
G01X1157963Y-123897D02*
G02I-12000J0D01*
G01X1152813D02*
G02I-6850J0D01*
G01X1145963Y-139897D02*
Y-107897D01*
G01X1161963Y-123897D02*
X1129963D01*
G54D15*
G01X-89222Y-207897D02*
Y-190397D01*
G01X-80052D02*
Y-207897D01*
G01Y-199147D02*
X-89222D01*
G01X-67137Y-207897D02*
X-68447Y-207605D01*
X-69757Y-206439D01*
X-70631Y-204397D01*
X-71067Y-202064D01*
X-70631Y-199730D01*
X-69757Y-197689D01*
X-68447Y-196522D01*
X-67137Y-196231D01*
X-65827Y-196522D01*
X-64517Y-197689D01*
X-63644Y-199730D01*
X-63425Y-202064D01*
X-63644Y-204397D01*
X-64517Y-206439D01*
X-65827Y-207605D01*
X-67137Y-207897D01*
G01X-53349D02*
Y-196231D01*
G01Y-199147D02*
X-52475Y-197689D01*
X-51165Y-196522D01*
X-49419Y-196231D01*
X-47891Y-196522D01*
X-46580Y-197689D01*
X-45925Y-199730D01*
Y-207897D01*
G01X-35412Y-200022D02*
X-28425D01*
X-29080Y-197980D01*
X-30172Y-196814D01*
X-31700Y-196231D01*
X-33229Y-196522D01*
X-34539Y-197397D01*
X-35412Y-199439D01*
X-35849Y-201189D01*
Y-202939D01*
X-35412Y-204689D01*
X-34320Y-206439D01*
X-33010Y-207605D01*
X-31482Y-207897D01*
X-29954Y-207314D01*
X-28425Y-205564D01*
G01X-19222Y-213147D02*
X-17912Y-213730D01*
X-16165Y-213147D01*
X-15074Y-211981D01*
X-14200Y-210522D01*
X-12891Y-205856D01*
X-10052Y-196231D01*
G01X-17039D02*
X-12891Y-205856D01*
G01X22109Y-198564D02*
X22983Y-197689D01*
X23638Y-196231D01*
X24075Y-194188D01*
X23638Y-192439D01*
X22765Y-191272D01*
X21236Y-190397D01*
X15341D01*
Y-207897D01*
X22546D01*
X24075Y-206731D01*
X24948Y-204980D01*
X25385Y-202939D01*
X24948Y-200897D01*
X23638Y-199147D01*
X22109Y-198564D01*
X15341D01*
G01X41793Y-207897D02*
Y-196231D01*
G01Y-198272D02*
X40920Y-197106D01*
X39609Y-196522D01*
X38081Y-196231D01*
X36553Y-196814D01*
X35243Y-197980D01*
X34369Y-199730D01*
X33933Y-202064D01*
X34369Y-204397D01*
X35243Y-206147D01*
X36553Y-207314D01*
X38081Y-207897D01*
X39609Y-207605D01*
X40920Y-206731D01*
X41793Y-205564D01*
G01X59293Y-190397D02*
Y-207897D01*
G01Y-205273D02*
X58420Y-206731D01*
X57109Y-207605D01*
X55581Y-207897D01*
X53835Y-207314D01*
X52525Y-205856D01*
X51651Y-204106D01*
X51433Y-202064D01*
X51651Y-200022D01*
X52525Y-198272D01*
X53835Y-196814D01*
X55581Y-196231D01*
X57109Y-196522D01*
X58201Y-197106D01*
X59293Y-198272D01*
G01X69806Y-212272D02*
X71335Y-213439D01*
X73081Y-213730D01*
X74609Y-213439D01*
X75920Y-211981D01*
X76793Y-209939D01*
Y-196231D01*
G01Y-198564D02*
X75920Y-197397D01*
X74609Y-196522D01*
X73081Y-196231D01*
X71335Y-196814D01*
X70243Y-197980D01*
X69369Y-200022D01*
X68933Y-202064D01*
X69151Y-203814D01*
X70025Y-205856D01*
X71335Y-207314D01*
X73081Y-207897D01*
X74391Y-207605D01*
X75920Y-206439D01*
X76793Y-205273D01*
G01X87088Y-200022D02*
X94075D01*
X93420Y-197980D01*
X92328Y-196814D01*
X90800Y-196231D01*
X89271Y-196522D01*
X87961Y-197397D01*
X87088Y-199439D01*
X86651Y-201189D01*
Y-202939D01*
X87088Y-204689D01*
X88180Y-206439D01*
X89490Y-207605D01*
X91018Y-207897D01*
X92546Y-207314D01*
X94075Y-205564D01*
G01X104806Y-207897D02*
Y-196231D01*
G01Y-198564D02*
X105898Y-197397D01*
X106990Y-196522D01*
X108518Y-196231D01*
X109609Y-196522D01*
X110920Y-197397D01*
G01X138060Y-207897D02*
Y-190397D01*
X142426D01*
X144173Y-191272D01*
X145483Y-192439D01*
X146575Y-194188D01*
X147448Y-196231D01*
X147666Y-199147D01*
X147448Y-202064D01*
X146575Y-204106D01*
X145483Y-205856D01*
X144173Y-207022D01*
X142426Y-207897D01*
X138060D01*
G01X155996D02*
Y-190397D01*
X161236D01*
X162983Y-191272D01*
X164293Y-193314D01*
X164730Y-195647D01*
X164293Y-197980D01*
X163201Y-199730D01*
X161236Y-200606D01*
X155996D01*
G01X179609Y-198564D02*
X180483Y-197689D01*
X181138Y-196231D01*
X181575Y-194188D01*
X181138Y-192439D01*
X180265Y-191272D01*
X178736Y-190397D01*
X172841D01*
Y-207897D01*
X180046D01*
X181575Y-206731D01*
X182448Y-204980D01*
X182885Y-202939D01*
X182448Y-200897D01*
X181138Y-199147D01*
X179609Y-198564D01*
X172841D01*
G01X208496Y-190397D02*
Y-207897D01*
X217230D01*
G01X230363D02*
X229053Y-207605D01*
X227743Y-206439D01*
X226869Y-204397D01*
X226433Y-202064D01*
X226869Y-199730D01*
X227743Y-197689D01*
X229053Y-196522D01*
X230363Y-196231D01*
X231673Y-196522D01*
X232983Y-197689D01*
X233856Y-199730D01*
X234075Y-202064D01*
X233856Y-204397D01*
X232983Y-206439D01*
X231673Y-207605D01*
X230363Y-207897D01*
G01X242404Y-196231D02*
X245025Y-207897D01*
X247863Y-196231D01*
X250701Y-207897D01*
X253322Y-196231D01*
G01X278496Y-190397D02*
Y-207897D01*
X287230D01*
G01X300363D02*
X299053Y-207605D01*
X297743Y-206439D01*
X296869Y-204397D01*
X296433Y-202064D01*
X296869Y-199730D01*
X297743Y-197689D01*
X299053Y-196522D01*
X300363Y-196231D01*
X301673Y-196522D01*
X302983Y-197689D01*
X303856Y-199730D01*
X304075Y-202064D01*
X303856Y-204397D01*
X302983Y-206439D01*
X301673Y-207605D01*
X300363Y-207897D01*
G01X314588Y-205856D02*
X315680Y-207022D01*
X317208Y-207897D01*
X318518D01*
X319828Y-207314D01*
X320701Y-206439D01*
X321138Y-205273D01*
X320920Y-203522D01*
X320046Y-202647D01*
X316116Y-200897D01*
X315243Y-198855D01*
X315680Y-197397D01*
X316553Y-196522D01*
X317863Y-196231D01*
X319173Y-196522D01*
X320483Y-197397D01*
G01X332088Y-205856D02*
X333180Y-207022D01*
X334708Y-207897D01*
X336018D01*
X337328Y-207314D01*
X338201Y-206439D01*
X338638Y-205273D01*
X338420Y-203522D01*
X337546Y-202647D01*
X333616Y-200897D01*
X332743Y-198855D01*
X333180Y-197397D01*
X334053Y-196522D01*
X335363Y-196231D01*
X336673Y-196522D01*
X337983Y-197397D01*
G01X-78741Y15000D02*
G03X-63741Y0I15000J0D01*
G01X-78741Y15000D02*
Y120047D01*
G01X-63741Y135047D02*
G03X-78741Y120047I0J-15000D01*
G01Y298866D02*
G03X-63741Y283866I15000J0D01*
G01X-78741Y319646D02*
Y298866D01*
G01X-63741Y334646D02*
G03X-78741Y319646I0J-15000D01*
G01Y908315D02*
G03X-63741Y893315I15000J0D01*
G01X-78741Y908315D02*
Y1104299D01*
G01X-63741Y1119299D02*
G03X-78741Y1104299I0J-15000D01*
G01Y1283118D02*
G03X-63741Y1268118I15000J0D01*
G01X-78741Y1304285D02*
Y1283118D01*
G01X-63741Y1319285D02*
G03X-78741Y1304285I0J-15000D01*
G01Y1892953D02*
G03X-63741Y1877953I15000J0D01*
G01X-78741Y1892953D02*
Y1977126D01*
G01X-63741Y1992126D02*
G03X-78741Y1977126I0J-15000D01*
G01X19882Y1197834D02*
X1969D01*
X0Y1195865D01*
Y832479D01*
X1969Y830511D01*
X19882D01*
G02Y823030I0J-3741D01*
G01X1969D01*
X0Y821062D01*
Y423030D01*
X1969Y421062D01*
X19882D01*
G02Y413582I0J-3740D01*
G01X1969D01*
X0Y411613D01*
Y223030D01*
X1969Y221062D01*
X19882D01*
G02Y213582I0J-3740D01*
G01X1969D01*
X0Y211613D01*
Y3936D01*
G03X3937Y-1I3937J0D01*
G01X1029528D01*
G03X1033465Y3936I0J3937D01*
G01Y1424881D01*
X1029528Y1428818D01*
X1024213D01*
G02X1019291Y1433739I-1J4921D01*
G01Y1607932D01*
X1015354Y1611869D01*
X989744D01*
G02Y1616082I0J2107D01*
G01X1015354D01*
X1019291Y1620019D01*
Y1676495D01*
G02X1024213Y1681416I4921J0D01*
G01X1029528D01*
X1033465Y1685353D01*
Y1988188D01*
G03X1029528Y1992125I-3937J0D01*
G01X3937D01*
G03X0Y1988188I0J-3937D01*
G01Y1816731D01*
X1969Y1814763D01*
X19882D01*
G02Y1807282I0J-3741D01*
G01X1969D01*
X0Y1805314D01*
Y1407282D01*
X1969Y1405314D01*
X19882D01*
G02Y1397834I0J-3740D01*
G01X1969D01*
X0Y1395865D01*
Y1207282D01*
X1969Y1205314D01*
X19882D01*
G02Y1197834I0J-3740D01*
G01X-7875Y0D02*
X-63741D01*
G01X-7875Y41772D02*
Y104969D01*
G01Y17252D02*
Y0D01*
G01Y41772D02*
G03X-1I3937J-1D01*
G01Y17213D02*
G03X-7875I-3937J0D01*
G01Y41772D02*
G03X-1I3937J-1D01*
G01Y17213D02*
G03X-7875I-3937J0D01*
G01Y129516D02*
Y135047D01*
G01D02*
X-63741D01*
G01X-7875Y129516D02*
G03X-1I3937J0D01*
G01Y104958D02*
G03X-7875I-3937J0D01*
G01Y283866D02*
Y300383D01*
G01X-19814Y283866D02*
X-63741D01*
G01X-7875D02*
X-19814D01*
G01X-1Y300383D02*
G03X-7875I-3937J0D01*
G01Y331986D02*
Y324003D01*
G01Y331986D02*
Y334646D01*
G01D02*
X-63741D01*
G01X-7875Y324003D02*
G03X-1I3937J0D01*
G01X-7875Y905988D02*
Y893315D01*
G01D02*
X-63741D01*
G01X-7875Y1069005D02*
Y933234D01*
G01D02*
G03X-1I3937J0D01*
G01Y905988D02*
G03X-7875I-3937J0D01*
G01Y1108863D02*
Y1119299D01*
G01X-19126D02*
X-7875D01*
G01X-15749D02*
X-63741D01*
G01X-7875Y1106300D02*
Y1111425D01*
G01Y1106300D02*
Y1092625D01*
G01D02*
G03X-1I3937J0D01*
G01Y1069005D02*
G03X-7875I-3937J0D01*
G01X-17894Y1268118D02*
X-7875D01*
G01Y1278280D02*
Y1268118D01*
G01Y1280567D02*
Y1275992D01*
G01X-15749Y1268118D02*
X-63741D01*
G01X-7875Y1309889D02*
G03X-1I3937J0D01*
G01Y1280567D02*
G03X-7875I-3937J0D01*
G01Y1309889D02*
G03X-1I3937J0D01*
G01Y1280567D02*
G03X-7875I-3937J0D01*
G01Y1309889D02*
Y1319285D01*
G01D02*
X-63741D01*
G01X-7875Y1889223D02*
Y1877953D01*
G01D02*
X-63741D01*
G01X-7875Y1912843D02*
Y1962926D01*
G01Y1912843D02*
G03X-1I3937J0D01*
G01Y1889223D02*
G03X-7875I-3937J0D01*
G01Y1912843D02*
G03X-1I3937J0D01*
G01Y1889223D02*
G03X-7875I-3937J0D01*
G01X-1Y1962926D02*
G03X-7875I-3937J0D01*
G01X-1D02*
G03X-7875I-3937J0D01*
G01Y1986546D02*
Y1992126D01*
G01D02*
X-63741D01*
G01X-7875Y1986546D02*
G03X-1I3937J0D01*
G01X-7875D02*
G03X-1I3937J0D01*
G01X94686Y-164897D02*
Y-147397D01*
X100363Y-161980D01*
X106040Y-147397D01*
Y-164897D01*
G01X117863D02*
X116553Y-164605D01*
X115243Y-163439D01*
X114369Y-161397D01*
X113933Y-159064D01*
X114369Y-156730D01*
X115243Y-154689D01*
X116553Y-153522D01*
X117863Y-153231D01*
X119173Y-153522D01*
X120483Y-154689D01*
X121356Y-156730D01*
X121575Y-159064D01*
X121356Y-161397D01*
X120483Y-163439D01*
X119173Y-164605D01*
X117863Y-164897D01*
G01X139293Y-147397D02*
Y-164897D01*
G01Y-162273D02*
X138420Y-163731D01*
X137109Y-164605D01*
X135581Y-164897D01*
X133835Y-164314D01*
X132525Y-162856D01*
X131651Y-161106D01*
X131433Y-159064D01*
X131651Y-157022D01*
X132525Y-155272D01*
X133835Y-153814D01*
X135581Y-153231D01*
X137109Y-153522D01*
X138201Y-154106D01*
X139293Y-155272D01*
G01X149588Y-157022D02*
X156575D01*
X155920Y-154980D01*
X154828Y-153814D01*
X153300Y-153231D01*
X151771Y-153522D01*
X150461Y-154397D01*
X149588Y-156439D01*
X149151Y-158189D01*
Y-159939D01*
X149588Y-161689D01*
X150680Y-163439D01*
X151990Y-164605D01*
X153518Y-164897D01*
X155046Y-164314D01*
X156575Y-162564D01*
G01X170363Y-164897D02*
Y-147397D01*
G01X376163Y-209897D02*
Y-192397D01*
X373543Y-195897D01*
G01Y-209897D02*
X378783D01*
G01X396283D02*
Y-192397D01*
X388204Y-204939D01*
X399122D01*
G01X406360Y-207273D02*
X407669Y-208731D01*
X409198Y-209605D01*
X411163Y-209897D01*
X413128Y-209314D01*
X414656Y-208147D01*
X415748Y-206106D01*
X415966Y-203772D01*
X415530Y-201439D01*
X414438Y-199980D01*
X412909Y-198814D01*
X411381Y-198522D01*
X409853Y-198814D01*
X407888Y-199980D01*
X408543Y-192397D01*
X414438D01*
G01X431283Y-209897D02*
Y-192397D01*
X423204Y-204939D01*
X434122D01*
G01X441360Y-207273D02*
X442669Y-208731D01*
X444198Y-209605D01*
X446163Y-209897D01*
X448128Y-209314D01*
X449656Y-208147D01*
X450748Y-206106D01*
X450966Y-203772D01*
X450530Y-201439D01*
X449438Y-199980D01*
X447909Y-198814D01*
X446381Y-198522D01*
X444853Y-198814D01*
X442888Y-199980D01*
X443543Y-192397D01*
X449438D01*
G01X363046Y-164897D02*
Y-147397D01*
X368286D01*
X370033Y-148272D01*
X371343Y-150314D01*
X371780Y-152647D01*
X371343Y-154980D01*
X370251Y-156730D01*
X368286Y-157606D01*
X363046D01*
G01X389716Y-148856D02*
X388406Y-147980D01*
X386878Y-147397D01*
X385131D01*
X383166Y-148272D01*
X381638Y-149730D01*
X380546Y-151481D01*
X379673Y-154397D01*
X379454Y-157022D01*
X379891Y-159647D01*
X380546Y-161397D01*
X381856Y-163147D01*
X383385Y-164314D01*
X384913Y-164897D01*
X386441D01*
X387970Y-164314D01*
X389280Y-163439D01*
X390372Y-162273D01*
G01X404159Y-155564D02*
X405033Y-154689D01*
X405688Y-153231D01*
X406125Y-151188D01*
X405688Y-149439D01*
X404815Y-148272D01*
X403286Y-147397D01*
X397391D01*
Y-164897D01*
X404596D01*
X406125Y-163731D01*
X406998Y-161980D01*
X407435Y-159939D01*
X406998Y-157897D01*
X405688Y-156147D01*
X404159Y-155564D01*
X397391D01*
G01X413363Y-170730D02*
X426463D01*
G01X432391Y-164897D02*
Y-147397D01*
X442435Y-164897D01*
Y-147397D01*
G01X454913Y-164897D02*
X453166Y-164605D01*
X451638Y-163439D01*
X450328Y-161689D01*
X449454Y-159647D01*
X449018Y-157314D01*
Y-154980D01*
X449454Y-152647D01*
X450328Y-150605D01*
X451638Y-148856D01*
X453166Y-147689D01*
X454913Y-147397D01*
X456659Y-147689D01*
X458188Y-148856D01*
X459498Y-150605D01*
X460372Y-152647D01*
X460808Y-154980D01*
Y-157314D01*
X460372Y-159647D01*
X459498Y-161689D01*
X458188Y-163439D01*
X456659Y-164605D01*
X454913Y-164897D01*
G01X505754Y-147397D02*
X511213Y-164897D01*
X516672Y-147397D01*
G01X533080Y-164897D02*
X524346D01*
Y-147397D01*
X533080D01*
G01X529586Y-155855D02*
X524346D01*
G01X541846Y-164897D02*
Y-147397D01*
X547305D01*
X549051Y-148272D01*
X550143Y-149439D01*
X550580Y-151772D01*
X550143Y-154106D01*
X548833Y-155564D01*
X547305Y-156439D01*
X541846D01*
G01X547305D02*
X550580Y-164897D01*
G01X563713Y-165480D02*
X563276Y-165189D01*
Y-164605D01*
X563713Y-164314D01*
X564150Y-164605D01*
Y-165189D01*
X563713Y-165480D01*
G01X524128Y-207564D02*
X525875Y-209022D01*
X527840Y-209897D01*
X529586D01*
X531333Y-209022D01*
X532643Y-207564D01*
X533298Y-205522D01*
X532861Y-203481D01*
X531770Y-201730D01*
X529805Y-200564D01*
X527185Y-199980D01*
X525656Y-198814D01*
X525001Y-196772D01*
X525438Y-194730D01*
X526530Y-193272D01*
X528058Y-192397D01*
X529586D01*
X531115Y-192980D01*
X532425Y-194439D01*
G01X540754Y-209897D02*
X546213Y-192397D01*
X551672Y-209897D01*
G01X549706Y-203772D02*
X542719D01*
G01X703167Y-200564D02*
X702293Y-199689D01*
X701638Y-198231D01*
X701201Y-196188D01*
X701638Y-194439D01*
X702511Y-193272D01*
X704040Y-192397D01*
X709935D01*
Y-209897D01*
X702730D01*
X701201Y-208731D01*
X700328Y-206980D01*
X699891Y-204939D01*
X700328Y-202897D01*
X701638Y-201147D01*
X703167Y-200564D01*
X709935D01*
G01X691998Y-207564D02*
X690251Y-209022D01*
X688286Y-209897D01*
X686540D01*
X684793Y-209022D01*
X683483Y-207564D01*
X682828Y-205522D01*
X683265Y-203481D01*
X684356Y-201730D01*
X686321Y-200564D01*
X688941Y-199980D01*
X690470Y-198814D01*
X691125Y-196772D01*
X690688Y-194730D01*
X689596Y-193272D01*
X688068Y-192397D01*
X686540D01*
X685011Y-192980D01*
X683701Y-194439D01*
G01X675590Y-209897D02*
Y-192397D01*
X669913Y-206980D01*
X664236Y-192397D01*
Y-209897D01*
G01X657216D02*
Y-192397D01*
X652850D01*
X651103Y-193272D01*
X649793Y-194439D01*
X648701Y-196188D01*
X647828Y-198231D01*
X647610Y-201147D01*
X647828Y-204064D01*
X648701Y-206106D01*
X649793Y-207856D01*
X651103Y-209022D01*
X652850Y-209897D01*
X657216D01*
G01X630546Y-147397D02*
Y-164897D01*
X639280D01*
G01X656343D02*
Y-153231D01*
G01Y-155272D02*
X655470Y-154106D01*
X654159Y-153522D01*
X652631Y-153231D01*
X651103Y-153814D01*
X649793Y-154980D01*
X648919Y-156730D01*
X648483Y-159064D01*
X648919Y-161397D01*
X649793Y-163147D01*
X651103Y-164314D01*
X652631Y-164897D01*
X654159Y-164605D01*
X655470Y-163731D01*
X656343Y-162564D01*
G01X665328Y-170147D02*
X666638Y-170730D01*
X668385Y-170147D01*
X669476Y-168981D01*
X670350Y-167522D01*
X671659Y-162856D01*
X674498Y-153231D01*
G01X667511D02*
X671659Y-162856D01*
G01X684138Y-157022D02*
X691125D01*
X690470Y-154980D01*
X689378Y-153814D01*
X687850Y-153231D01*
X686321Y-153522D01*
X685011Y-154397D01*
X684138Y-156439D01*
X683701Y-158189D01*
Y-159939D01*
X684138Y-161689D01*
X685230Y-163439D01*
X686540Y-164605D01*
X688068Y-164897D01*
X689596Y-164314D01*
X691125Y-162564D01*
G01X701856Y-164897D02*
Y-153231D01*
G01Y-155564D02*
X702948Y-154397D01*
X704040Y-153522D01*
X705568Y-153231D01*
X706659Y-153522D01*
X707970Y-154397D01*
G01X719138Y-162856D02*
X720230Y-164022D01*
X721758Y-164897D01*
X723068D01*
X724378Y-164314D01*
X725251Y-163439D01*
X725688Y-162273D01*
X725470Y-160522D01*
X724596Y-159647D01*
X720666Y-157897D01*
X719793Y-155855D01*
X720230Y-154397D01*
X721103Y-153522D01*
X722413Y-153231D01*
X723723Y-153522D01*
X725033Y-154397D01*
G01X790596Y-209897D02*
Y-192397D01*
X796055D01*
X797801Y-193272D01*
X798893Y-194439D01*
X799330Y-196772D01*
X798893Y-199106D01*
X797583Y-200564D01*
X796055Y-201439D01*
X790596D01*
G01X796055D02*
X799330Y-209897D01*
G01X809188Y-202022D02*
X816175D01*
X815520Y-199980D01*
X814428Y-198814D01*
X812900Y-198231D01*
X811371Y-198522D01*
X810061Y-199397D01*
X809188Y-201439D01*
X808751Y-203189D01*
Y-204939D01*
X809188Y-206689D01*
X810280Y-208439D01*
X811590Y-209605D01*
X813118Y-209897D01*
X814646Y-209314D01*
X816175Y-207564D01*
G01X826033Y-209897D02*
Y-192397D01*
G01Y-201147D02*
X827125Y-199397D01*
X828435Y-198522D01*
X829745Y-198231D01*
X831709Y-198814D01*
X833020Y-199980D01*
X833893Y-202022D01*
Y-204355D01*
X833456Y-206689D01*
X832583Y-208439D01*
X831055Y-209605D01*
X829745Y-209897D01*
X828435Y-209605D01*
X827125Y-208731D01*
X826033Y-207273D01*
G01X844188Y-202022D02*
X851175D01*
X850520Y-199980D01*
X849428Y-198814D01*
X847900Y-198231D01*
X846371Y-198522D01*
X845061Y-199397D01*
X844188Y-201439D01*
X843751Y-203189D01*
Y-204939D01*
X844188Y-206689D01*
X845280Y-208439D01*
X846590Y-209605D01*
X848118Y-209897D01*
X849646Y-209314D01*
X851175Y-207564D01*
G01X868456Y-199689D02*
X866928Y-198522D01*
X865618Y-198231D01*
X863871Y-198814D01*
X862561Y-199980D01*
X861688Y-202022D01*
X861469Y-204064D01*
X861688Y-206106D01*
X862561Y-207856D01*
X863871Y-209314D01*
X865618Y-209897D01*
X867146Y-209314D01*
X868456Y-208147D01*
G01X885956Y-199689D02*
X884428Y-198522D01*
X883118Y-198231D01*
X881371Y-198814D01*
X880061Y-199980D01*
X879188Y-202022D01*
X878969Y-204064D01*
X879188Y-206106D01*
X880061Y-207856D01*
X881371Y-209314D01*
X883118Y-209897D01*
X884646Y-209314D01*
X885956Y-208147D01*
G01X903893Y-209897D02*
Y-198231D01*
G01Y-200272D02*
X903020Y-199106D01*
X901709Y-198522D01*
X900181Y-198231D01*
X898653Y-198814D01*
X897343Y-199980D01*
X896469Y-201730D01*
X896033Y-204064D01*
X896469Y-206397D01*
X897343Y-208147D01*
X898653Y-209314D01*
X900181Y-209897D01*
X901709Y-209605D01*
X903020Y-208731D01*
X903893Y-207564D01*
G01X781410Y-164897D02*
Y-147397D01*
X785776D01*
X787523Y-148272D01*
X788833Y-149439D01*
X789925Y-151188D01*
X790798Y-153231D01*
X791016Y-156147D01*
X790798Y-159064D01*
X789925Y-161106D01*
X788833Y-162856D01*
X787523Y-164022D01*
X785776Y-164897D01*
X781410D01*
G01X800438Y-157022D02*
X807425D01*
X806770Y-154980D01*
X805678Y-153814D01*
X804150Y-153231D01*
X802621Y-153522D01*
X801311Y-154397D01*
X800438Y-156439D01*
X800001Y-158189D01*
Y-159939D01*
X800438Y-161689D01*
X801530Y-163439D01*
X802840Y-164605D01*
X804368Y-164897D01*
X805896Y-164314D01*
X807425Y-162564D01*
G01X817938Y-162856D02*
X819030Y-164022D01*
X820558Y-164897D01*
X821868D01*
X823178Y-164314D01*
X824051Y-163439D01*
X824488Y-162273D01*
X824270Y-160522D01*
X823396Y-159647D01*
X819466Y-157897D01*
X818593Y-155855D01*
X819030Y-154397D01*
X819903Y-153522D01*
X821213Y-153231D01*
X822523Y-153522D01*
X823833Y-154397D01*
G01X838713Y-153231D02*
Y-164897D01*
G01Y-148564D02*
X838276Y-148272D01*
Y-147689D01*
X838713Y-147397D01*
X839150Y-147689D01*
Y-148272D01*
X838713Y-148564D01*
G01X853156Y-169272D02*
X854685Y-170439D01*
X856431Y-170730D01*
X857959Y-170439D01*
X859270Y-168981D01*
X860143Y-166939D01*
Y-153231D01*
G01Y-155564D02*
X859270Y-154397D01*
X857959Y-153522D01*
X856431Y-153231D01*
X854685Y-153814D01*
X853593Y-154980D01*
X852719Y-157022D01*
X852283Y-159064D01*
X852501Y-160814D01*
X853375Y-162856D01*
X854685Y-164314D01*
X856431Y-164897D01*
X857741Y-164605D01*
X859270Y-163439D01*
X860143Y-162273D01*
G01X870001Y-164897D02*
Y-153231D01*
G01Y-156147D02*
X870875Y-154689D01*
X872185Y-153522D01*
X873931Y-153231D01*
X875459Y-153522D01*
X876770Y-154689D01*
X877425Y-156730D01*
Y-164897D01*
G01X887938Y-157022D02*
X894925D01*
X894270Y-154980D01*
X893178Y-153814D01*
X891650Y-153231D01*
X890121Y-153522D01*
X888811Y-154397D01*
X887938Y-156439D01*
X887501Y-158189D01*
Y-159939D01*
X887938Y-161689D01*
X889030Y-163439D01*
X890340Y-164605D01*
X891868Y-164897D01*
X893396Y-164314D01*
X894925Y-162564D01*
G01X905656Y-164897D02*
Y-153231D01*
G01Y-155564D02*
X906748Y-154397D01*
X907840Y-153522D01*
X909368Y-153231D01*
X910459Y-153522D01*
X911770Y-154397D01*
G01X952413Y-192397D02*
X950666Y-192980D01*
X949356Y-194439D01*
X948483Y-196188D01*
X947828Y-198522D01*
X947610Y-201147D01*
X947828Y-203772D01*
X948483Y-206106D01*
X949356Y-207856D01*
X950666Y-209314D01*
X952413Y-209897D01*
X954159Y-209314D01*
X955470Y-207856D01*
X956343Y-206106D01*
X956998Y-203772D01*
X957216Y-201147D01*
X956998Y-198522D01*
X956343Y-196188D01*
X955470Y-194439D01*
X954159Y-192980D01*
X952413Y-192397D01*
G01X969913Y-209897D02*
X971441Y-209605D01*
X973188Y-208731D01*
X974280Y-207273D01*
X974716Y-205230D01*
X974280Y-203189D01*
X972970Y-201439D01*
X971005Y-200564D01*
X968821D01*
X967511Y-199980D01*
X966419Y-198522D01*
X965983Y-196481D01*
X966638Y-194439D01*
X968166Y-192980D01*
X969913Y-192397D01*
X971659Y-192980D01*
X973188Y-194439D01*
X973843Y-196481D01*
X973406Y-198522D01*
X972315Y-199980D01*
X971005Y-200564D01*
X968821D01*
X966856Y-201439D01*
X965546Y-203189D01*
X965110Y-205230D01*
X965546Y-207273D01*
X966638Y-208731D01*
X968385Y-209605D01*
X969913Y-209897D01*
G01X983483Y-210480D02*
X991343Y-192397D01*
G01X1004913D02*
X1003166Y-192980D01*
X1001856Y-194439D01*
X1000983Y-196188D01*
X1000328Y-198522D01*
X1000110Y-201147D01*
X1000328Y-203772D01*
X1000983Y-206106D01*
X1001856Y-207856D01*
X1003166Y-209314D01*
X1004913Y-209897D01*
X1006659Y-209314D01*
X1007970Y-207856D01*
X1008843Y-206106D01*
X1009498Y-203772D01*
X1009716Y-201147D01*
X1009498Y-198522D01*
X1008843Y-196188D01*
X1007970Y-194439D01*
X1006659Y-192980D01*
X1004913Y-192397D01*
G01X1022413Y-209897D02*
Y-192397D01*
X1019793Y-195897D01*
G01Y-209897D02*
X1025033D01*
G01X1035983Y-210480D02*
X1043843Y-192397D01*
G01X1053265Y-195314D02*
X1054575Y-193564D01*
X1056103Y-192689D01*
X1057850Y-192397D01*
X1060033Y-192980D01*
X1061561Y-194439D01*
X1061998Y-196188D01*
X1061780Y-197939D01*
X1060906Y-199397D01*
X1056540Y-202314D01*
X1054575Y-204355D01*
X1053265Y-207273D01*
X1052828Y-209897D01*
X1061998D01*
G01X1074913Y-192397D02*
X1073166Y-192980D01*
X1071856Y-194439D01*
X1070983Y-196188D01*
X1070328Y-198522D01*
X1070110Y-201147D01*
X1070328Y-203772D01*
X1070983Y-206106D01*
X1071856Y-207856D01*
X1073166Y-209314D01*
X1074913Y-209897D01*
X1076659Y-209314D01*
X1077970Y-207856D01*
X1078843Y-206106D01*
X1079498Y-203772D01*
X1079716Y-201147D01*
X1079498Y-198522D01*
X1078843Y-196188D01*
X1077970Y-194439D01*
X1076659Y-192980D01*
X1074913Y-192397D01*
G01X1092413Y-209897D02*
Y-192397D01*
X1089793Y-195897D01*
G01Y-209897D02*
X1095033D01*
G01X1112533D02*
Y-192397D01*
X1104454Y-204939D01*
X1115372D01*
G01X1000110Y-164897D02*
Y-147397D01*
X1004476D01*
X1006223Y-148272D01*
X1007533Y-149439D01*
X1008625Y-151188D01*
X1009498Y-153231D01*
X1009716Y-156147D01*
X1009498Y-159064D01*
X1008625Y-161106D01*
X1007533Y-162856D01*
X1006223Y-164022D01*
X1004476Y-164897D01*
X1000110D01*
G01X1026343D02*
Y-153231D01*
G01Y-155272D02*
X1025470Y-154106D01*
X1024159Y-153522D01*
X1022631Y-153231D01*
X1021103Y-153814D01*
X1019793Y-154980D01*
X1018919Y-156730D01*
X1018483Y-159064D01*
X1018919Y-161397D01*
X1019793Y-163147D01*
X1021103Y-164314D01*
X1022631Y-164897D01*
X1024159Y-164605D01*
X1025470Y-163731D01*
X1026343Y-162564D01*
G01X1039913Y-147397D02*
Y-164897D01*
G01X1036856Y-153231D02*
X1042970D01*
G01X1054138Y-157022D02*
X1061125D01*
X1060470Y-154980D01*
X1059378Y-153814D01*
X1057850Y-153231D01*
X1056321Y-153522D01*
X1055011Y-154397D01*
X1054138Y-156439D01*
X1053701Y-158189D01*
Y-159939D01*
X1054138Y-161689D01*
X1055230Y-163439D01*
X1056540Y-164605D01*
X1058068Y-164897D01*
X1059596Y-164314D01*
X1061125Y-162564D01*
G01X1041337Y24677D02*
Y0D01*
G01Y217343D02*
Y48297D01*
G01Y0D02*
X1097204D01*
G01X1033463Y48297D02*
G03X1041337I3937J0D01*
G01Y24677D02*
G03X1033463I-3937J0D01*
G01Y48297D02*
G03X1041337I3937J0D01*
G01Y24677D02*
G03X1033463I-3937J0D01*
G01X1041337Y217343D02*
G03X1033463I-3937J0D01*
G01X1041337D02*
G03X1033463I-3937J0D01*
G01X1041337Y445039D02*
Y240963D01*
G01X1033463D02*
G03X1041337I3937J0D01*
G01X1033463D02*
G03X1041337I3937J0D01*
G01Y697474D02*
Y468601D01*
G01X1033463Y468659D02*
G03X1041337I3937J0D01*
G01Y445039D02*
G03X1033463I-3937J0D01*
G01Y468659D02*
G03X1041337I3937J0D01*
G01Y445039D02*
G03X1033463I-3937J0D01*
G01X1041337Y996851D02*
Y721093D01*
G01X1033463D02*
G03X1041337I3937J0D01*
G01Y697474D02*
G03X1033463I-3937J-1D01*
G01Y721093D02*
G03X1041337I3937J0D01*
G01Y697474D02*
G03X1033463I-3937J-1D01*
G01X1041337Y1344059D02*
Y1020472D01*
G01X1033463D02*
G03X1041337I3937J0D01*
G01Y996851D02*
G03X1033463I-3937J1D01*
G01Y1020472D02*
G03X1041337I3937J0D01*
G01Y996851D02*
G03X1033463I-3937J1D01*
G01X1041337Y1367679D02*
Y1393701D01*
G01X1033463Y1367679D02*
G03X1041337I3937J0D01*
G01Y1344059D02*
G03X1033463I-3937J0D01*
G01Y1367679D02*
G03X1041337I3937J0D01*
G01Y1344059D02*
G03X1033463I-3937J0D01*
G01X1041337Y1393701D02*
X1097204D01*
G01X1041337Y1733129D02*
Y1716535D01*
G01X1065042D02*
X1041337D01*
G01X1056337D02*
X1097204D01*
G01X1041337Y1739719D02*
Y1731535D01*
G01Y1959242D02*
Y1763311D01*
G01X1033463Y1763339D02*
G03X1041337I3937J0D01*
G01Y1739719D02*
G03X1033463I-3937J0D01*
G01Y1763339D02*
G03X1041337I3937J0D01*
G01Y1739719D02*
G03X1033463I-3937J0D01*
G01X1041337Y1959242D02*
G03X1033463I-3937J0D01*
G01X1041337D02*
G03X1033463I-3937J0D01*
G01X1041337Y1992126D02*
X1097204D01*
G01X1041337Y1982862D02*
Y1992126D01*
G01X1033463Y1982862D02*
G03X1041337I3937J0D01*
G01X1033463D02*
G03X1041337I3937J0D01*
G01X1112204Y648419D02*
Y15000D01*
G01X1097204Y0D02*
G03X1112204Y15000I0J15000D01*
G01Y656293D02*
G03Y648419I0J-3937D01*
G01Y1378701D02*
Y656293D01*
G01Y1378701D02*
G03X1097204Y1393701I-15000J0D01*
G01Y1716535D02*
G03X1112204Y1731535I0J15000D01*
G01Y1977126D02*
Y1731535D01*
G01Y1977126D02*
G03X1097204Y1992126I-15000J0D01*
M02*
